(kicad_pcb
	(version 20260206)
	(generator "pcbnew")
	(generator_version "10.0")
	(general
		(thickness 1.6)
		(legacy_teardrops no)
	)
	(paper "A4")
	(title_block
		(title "04192023_DAF0TMB3IC0_F0TG_MB_C_brd_V02_OCP.brd")
		(comment 1 "Grand Teton / footprints 2401-2407 of 8354")
	)
	(layers
		(0 "F.Cu" signal "TOP")
		(4 "In1.Cu" signal "GND")
		(6 "In2.Cu" signal "IN1")
		(8 "In3.Cu" signal "GND1")
		(10 "In4.Cu" signal "IN2")
		(12 "In5.Cu" signal "GND2")
		(14 "In6.Cu" signal "IN3")
		(16 "In7.Cu" signal "GND3")
		(18 "In8.Cu" signal "VCC")
		(20 "In9.Cu" signal "VCC1")
		(22 "In10.Cu" signal "GND4")
		(24 "In11.Cu" signal "IN4")
		(26 "In12.Cu" signal "GND5")
		(28 "In13.Cu" signal "IN5")
		(30 "In14.Cu" signal "GND6")
		(32 "In15.Cu" signal "IN6")
		(34 "In16.Cu" signal "GND7")
		(2 "B.Cu" signal "BOTTOM")
		(9 "F.Adhes" user "F.Adhesive")
		(11 "B.Adhes" user "B.Adhesive")
		(13 "F.Paste" user "Package Geometry/Pastemask Top")
		(15 "B.Paste" user "Package Geometry/Pastemask Bottom")
		(5 "F.SilkS" user "Ref Des/Silkscreen Top")
		(7 "B.SilkS" user "Ref Des/Silkscreen Bottom")
		(1 "F.Mask" user "Board Geometry/Soldermask Top")
		(3 "B.Mask" user "Board Geometry/Soldermask Bottom")
		(17 "Dwgs.User" user "User.Drawings")
		(19 "Cmts.User" user "User.Comments")
		(21 "Eco1.User" user "User.Eco1")
		(23 "Eco2.User" user "User.Eco2")
		(25 "Edge.Cuts" user "Board Geometry/Outline")
		(27 "Margin" user)
		(31 "F.CrtYd" user "Package Geometry/Place Bound Top")
		(29 "B.CrtYd" user "Package Geometry/Place Bound Bottom")
		(35 "F.Fab" user "Ref Des/Assembly Top")
		(33 "B.Fab" user "Ref Des/Assembly Bottom")
	)
	(footprint ""
		(layer "F.Cu")
		(at 33.63468 -432.564794 90)
		(property "Reference" "R2894"
			(at 0 0 90)
			(layer "F.SilkS")
			(hide yes)
			(effects
				(font
					(size 1.27 1.27)
				)
			)
		)
		(property "Value" ""
			(at 0 0 90)
			(layer "F.Fab")
			(effects
				(font
					(size 1.27 1.27)
				)
			)
		)
		(duplicate_pad_numbers_are_jumpers no)
		(fp_line
			(start 0.7874 -0.4064)
			(end 0.7874 0.4064)
			(stroke
				(width 0.1524)
				(type default)
			)
			(layer "F.SilkS")
		)
		(fp_line
			(start -0.7874 -0.4064)
			(end 0.7874 -0.4064)
			(stroke
				(width 0.1524)
				(type default)
			)
			(layer "F.SilkS")
		)
		(fp_line
			(start 0.7874 0.4064)
			(end -0.7874 0.4064)
			(stroke
				(width 0.1524)
				(type default)
			)
			(layer "F.SilkS")
		)
		(fp_line
			(start -0.7874 0.4064)
			(end -0.7874 -0.4064)
			(stroke
				(width 0.1524)
				(type default)
			)
			(layer "F.SilkS")
		)
		(fp_line
			(start -0.12065 -0.305054)
			(end -0.12065 -0.2794)
			(stroke
				(width 0.1)
				(type default)
			)
			(layer "F.Fab")
		)
		(fp_line
			(start -0.67945 -0.305054)
			(end -0.12065 -0.305054)
			(stroke
				(width 0.1)
				(type default)
			)
			(layer "F.Fab")
		)
		(fp_line
			(start 0.67945 -0.3048)
			(end 0.67945 0.3048)
			(stroke
				(width 0.1)
				(type default)
			)
			(layer "F.Fab")
		)
		(fp_line
			(start 0.12065 -0.3048)
			(end 0.67945 -0.3048)
			(stroke
				(width 0.1)
				(type default)
			)
			(layer "F.Fab")
		)
		(fp_line
			(start 0.12065 -0.2794)
			(end 0.12065 -0.3048)
			(stroke
				(width 0.1)
				(type default)
			)
			(layer "F.Fab")
		)
		(fp_line
			(start -0.12065 -0.2794)
			(end 0.12065 -0.2794)
			(stroke
				(width 0.1)
				(type default)
			)
			(layer "F.Fab")
		)
		(fp_line
			(start 0.120396 0.2794)
			(end -0.12065 0.2794)
			(stroke
				(width 0.1)
				(type default)
			)
			(layer "F.Fab")
		)
		(fp_line
			(start -0.12065 0.2794)
			(end -0.12065 0.3048)
			(stroke
				(width 0.1)
				(type default)
			)
			(layer "F.Fab")
		)
		(fp_line
			(start 0.67945 0.3048)
			(end 0.120396 0.3048)
			(stroke
				(width 0.1)
				(type default)
			)
			(layer "F.Fab")
		)
		(fp_line
			(start 0.120396 0.3048)
			(end 0.120396 0.2794)
			(stroke
				(width 0.1)
				(type default)
			)
			(layer "F.Fab")
		)
		(fp_line
			(start -0.12065 0.3048)
			(end -0.67945 0.3048)
			(stroke
				(width 0.1)
				(type default)
			)
			(layer "F.Fab")
		)
		(fp_line
			(start -0.67945 0.3048)
			(end -0.67945 -0.305054)
			(stroke
				(width 0.1)
				(type default)
			)
			(layer "F.Fab")
		)
		(pad "1" smd circle
			(at -0.40005 0 90)
			(size 0 0)
			(layers "F.Cu" "F.Mask" "F.Paste")
			(net "SMB_1_BMC_GPU_R_SDA")
		)
		(pad "2" smd circle
			(at 0.40005 0 90)
			(size 0 0)
			(layers "F.Cu" "F.Mask" "F.Paste")
			(net "SMB_1_BMC_GPU_BUF_R_SDA")
		)
	)
	(footprint ""
		(layer "F.Cu")
		(at 303.69383 -152.875742 180)
		(property "Reference" "TP4"
			(at 2.89814 -0.282194 0)
			(unlocked yes)
			(layer "F.SilkS")
			(effects
				(font
					(size 0.7874 0.5842)
					(thickness 0.1524)
				)
				(justify left)
			)
		)
		(property "Value" ""
			(at 0 0 180)
			(layer "F.Fab")
			(effects
				(font
					(size 1.27 1.27)
				)
			)
		)
		(duplicate_pad_numbers_are_jumpers no)
		(pad "1" smd circle
			(at 0 0 180)
			(size 0.762 0.762)
			(layers "F.Cu" "F.Mask" "F.Paste")
			(net "VSENSE_PVDD18_S5_P0_DN")
		)
	)
	(footprint ""
		(layer "F.Cu")
		(at 98.795078 -145.06321 180)
		(property "Reference" "PR159"
			(at 0 0 180)
			(layer "F.SilkS")
			(hide yes)
			(effects
				(font
					(size 1.27 1.27)
				)
			)
		)
		(property "Value" ""
			(at 0 0 180)
			(layer "F.Fab")
			(effects
				(font
					(size 1.27 1.27)
				)
			)
		)
		(duplicate_pad_numbers_are_jumpers no)
		(fp_line
			(start 0.7874 0.4064)
			(end -0.7874 0.4064)
			(stroke
				(width 0.1524)
				(type default)
			)
			(layer "F.SilkS")
		)
		(fp_line
			(start 0.7874 -0.4064)
			(end 0.7874 0.4064)
			(stroke
				(width 0.1524)
				(type default)
			)
			(layer "F.SilkS")
		)
		(fp_line
			(start -0.7874 0.4064)
			(end -0.7874 -0.4064)
			(stroke
				(width 0.1524)
				(type default)
			)
			(layer "F.SilkS")
		)
		(fp_line
			(start -0.7874 -0.4064)
			(end 0.7874 -0.4064)
			(stroke
				(width 0.1524)
				(type default)
			)
			(layer "F.SilkS")
		)
		(fp_line
			(start 0.67945 0.3048)
			(end 0.120396 0.3048)
			(stroke
				(width 0.1)
				(type default)
			)
			(layer "F.Fab")
		)
		(fp_line
			(start 0.67945 -0.3048)
			(end 0.67945 0.3048)
			(stroke
				(width 0.1)
				(type default)
			)
			(layer "F.Fab")
		)
		(fp_line
			(start 0.12065 -0.2794)
			(end 0.12065 -0.3048)
			(stroke
				(width 0.1)
				(type default)
			)
			(layer "F.Fab")
		)
		(fp_line
			(start 0.12065 -0.3048)
			(end 0.67945 -0.3048)
			(stroke
				(width 0.1)
				(type default)
			)
			(layer "F.Fab")
		)
		(fp_line
			(start 0.120396 0.3048)
			(end 0.120396 0.2794)
			(stroke
				(width 0.1)
				(type default)
			)
			(layer "F.Fab")
		)
		(fp_line
			(start 0.120396 0.2794)
			(end -0.12065 0.2794)
			(stroke
				(width 0.1)
				(type default)
			)
			(layer "F.Fab")
		)
		(fp_line
			(start -0.12065 0.3048)
			(end -0.67945 0.3048)
			(stroke
				(width 0.1)
				(type default)
			)
			(layer "F.Fab")
		)
		(fp_line
			(start -0.12065 0.2794)
			(end -0.12065 0.3048)
			(stroke
				(width 0.1)
				(type default)
			)
			(layer "F.Fab")
		)
		(fp_line
			(start -0.12065 -0.2794)
			(end 0.12065 -0.2794)
			(stroke
				(width 0.1)
				(type default)
			)
			(layer "F.Fab")
		)
		(fp_line
			(start -0.12065 -0.305054)
			(end -0.12065 -0.2794)
			(stroke
				(width 0.1)
				(type default)
			)
			(layer "F.Fab")
		)
		(fp_line
			(start -0.67945 0.3048)
			(end -0.67945 -0.305054)
			(stroke
				(width 0.1)
				(type default)
			)
			(layer "F.Fab")
		)
		(fp_line
			(start -0.67945 -0.305054)
			(end -0.12065 -0.305054)
			(stroke
				(width 0.1)
				(type default)
			)
			(layer "F.Fab")
		)
		(pad "1" smd circle
			(at -0.40005 0 180)
			(size 0 0)
			(layers "F.Cu" "F.Mask" "F.Paste")
			(net "PVDDCR_SOC_P1_EN//ADDR_CFG")
		)
		(pad "2" smd circle
			(at 0.40005 0 180)
			(size 0 0)
			(layers "F.Cu" "F.Mask" "F.Paste")
			(net "GND")
		)
	)
	(footprint ""
		(layer "F.Cu")
		(at 368.427 -411.226 90)
		(property "Reference" "R4211"
			(at 0 0 90)
			(layer "F.SilkS")
			(hide yes)
			(effects
				(font
					(size 1.27 1.27)
				)
			)
		)
		(property "Value" ""
			(at 0 0 90)
			(layer "F.Fab")
			(effects
				(font
					(size 1.27 1.27)
				)
			)
		)
		(duplicate_pad_numbers_are_jumpers no)
		(fp_line
			(start 0.7874 -0.4064)
			(end 0.7874 0.4064)
			(stroke
				(width 0.1524)
				(type default)
			)
			(layer "F.SilkS")
		)
		(fp_line
			(start -0.7874 -0.4064)
			(end 0.7874 -0.4064)
			(stroke
				(width 0.1524)
				(type default)
			)
			(layer "F.SilkS")
		)
		(fp_line
			(start 0.7874 0.4064)
			(end -0.7874 0.4064)
			(stroke
				(width 0.1524)
				(type default)
			)
			(layer "F.SilkS")
		)
		(fp_line
			(start -0.7874 0.4064)
			(end -0.7874 -0.4064)
			(stroke
				(width 0.1524)
				(type default)
			)
			(layer "F.SilkS")
		)
		(fp_line
			(start -0.12065 -0.305054)
			(end -0.12065 -0.2794)
			(stroke
				(width 0.1)
				(type default)
			)
			(layer "F.Fab")
		)
		(fp_line
			(start -0.67945 -0.305054)
			(end -0.12065 -0.305054)
			(stroke
				(width 0.1)
				(type default)
			)
			(layer "F.Fab")
		)
		(fp_line
			(start 0.67945 -0.3048)
			(end 0.67945 0.3048)
			(stroke
				(width 0.1)
				(type default)
			)
			(layer "F.Fab")
		)
		(fp_line
			(start 0.12065 -0.3048)
			(end 0.67945 -0.3048)
			(stroke
				(width 0.1)
				(type default)
			)
			(layer "F.Fab")
		)
		(fp_line
			(start 0.12065 -0.2794)
			(end 0.12065 -0.3048)
			(stroke
				(width 0.1)
				(type default)
			)
			(layer "F.Fab")
		)
		(fp_line
			(start -0.12065 -0.2794)
			(end 0.12065 -0.2794)
			(stroke
				(width 0.1)
				(type default)
			)
			(layer "F.Fab")
		)
		(fp_line
			(start 0.120396 0.2794)
			(end -0.12065 0.2794)
			(stroke
				(width 0.1)
				(type default)
			)
			(layer "F.Fab")
		)
		(fp_line
			(start -0.12065 0.2794)
			(end -0.12065 0.3048)
			(stroke
				(width 0.1)
				(type default)
			)
			(layer "F.Fab")
		)
		(fp_line
			(start 0.67945 0.3048)
			(end 0.120396 0.3048)
			(stroke
				(width 0.1)
				(type default)
			)
			(layer "F.Fab")
		)
		(fp_line
			(start 0.120396 0.3048)
			(end 0.120396 0.2794)
			(stroke
				(width 0.1)
				(type default)
			)
			(layer "F.Fab")
		)
		(fp_line
			(start -0.12065 0.3048)
			(end -0.67945 0.3048)
			(stroke
				(width 0.1)
				(type default)
			)
			(layer "F.Fab")
		)
		(fp_line
			(start -0.67945 0.3048)
			(end -0.67945 -0.305054)
			(stroke
				(width 0.1)
				(type default)
			)
			(layer "F.Fab")
		)
		(pad "1" smd circle
			(at -0.40005 0 90)
			(size 0 0)
			(layers "F.Cu" "F.Mask" "F.Paste")
			(net "P3V3_AUX")
		)
		(pad "2" smd circle
			(at 0.40005 0 90)
			(size 0 0)
			(layers "F.Cu" "F.Mask" "F.Paste")
			(net "FM_THERMAL_ALERT_N")
		)
	)
	(footprint ""
		(layer "F.Cu")
		(at 111.4298 -332.733142 90)
		(property "Reference" "PL39"
			(at -3.302 4.022852 90)
			(unlocked yes)
			(layer "F.SilkS")
			(effects
				(font
					(size 0.7874 0.5842)
					(thickness 0.1524)
				)
				(justify left)
			)
		)
		(property "Value" ""
			(at 0 0 90)
			(layer "F.Fab")
			(effects
				(font
					(size 1.27 1.27)
				)
			)
		)
		(duplicate_pad_numbers_are_jumpers no)
		(fp_line
			(start 3.24993 -3.24993)
			(end 3.24993 -2.2352)
			(stroke
				(width 0.1524)
				(type default)
			)
			(layer "F.SilkS")
		)
		(fp_line
			(start -3.24993 -3.24993)
			(end 3.24993 -3.24993)
			(stroke
				(width 0.1524)
				(type default)
			)
			(layer "F.SilkS")
		)
		(fp_line
			(start -3.24993 -2.2352)
			(end -3.24993 -3.24993)
			(stroke
				(width 0.1524)
				(type default)
			)
			(layer "F.SilkS")
		)
		(fp_line
			(start 3.24993 2.2352)
			(end 3.24993 3.24993)
			(stroke
				(width 0.1524)
				(type default)
			)
			(layer "F.SilkS")
		)
		(fp_line
			(start 3.24993 3.24993)
			(end -3.24993 3.24993)
			(stroke
				(width 0.1524)
				(type default)
			)
			(layer "F.SilkS")
		)
		(fp_line
			(start -3.24993 3.24993)
			(end -3.24993 2.2352)
			(stroke
				(width 0.1524)
				(type default)
			)
			(layer "F.SilkS")
		)
		(fp_line
			(start 3.24993 -3.24993)
			(end 3.24993 3.24993)
			(stroke
				(width 0.1)
				(type default)
			)
			(layer "F.Fab")
		)
		(fp_line
			(start -3.24993 -3.24993)
			(end 3.24993 -3.24993)
			(stroke
				(width 0.1)
				(type default)
			)
			(layer "F.Fab")
		)
		(fp_line
			(start 3.24993 3.24993)
			(end -3.24993 3.24993)
			(stroke
				(width 0.1)
				(type default)
			)
			(layer "F.Fab")
		)
		(fp_line
			(start -3.24993 3.24993)
			(end -3.24993 -3.24993)
			(stroke
				(width 0.1)
				(type default)
			)
			(layer "F.Fab")
		)
		(pad "1" smd rect
			(at -2.29997 0 90)
			(size 2.0066 4.2164)
			(layers "F.Cu" "F.Mask" "F.Paste")
			(net "IND_CPU1_P1_CPL0")
		)
		(pad "2" smd rect
			(at 2.29997 0 90)
			(size 2.0066 4.2164)
			(layers "F.Cu" "F.Mask" "F.Paste")
			(net "GND")
		)
	)
	(footprint ""
		(layer "F.Cu")
		(at 243.446808 -42.063162 -90)
		(property "Reference" "C1276"
			(at 0 0 270)
			(layer "F.SilkS")
			(hide yes)
			(effects
				(font
					(size 1.27 1.27)
				)
			)
		)
		(property "Value" ""
			(at 0 0 270)
			(layer "F.Fab")
			(effects
				(font
					(size 1.27 1.27)
				)
			)
		)
		(duplicate_pad_numbers_are_jumpers no)
		(fp_line
			(start -1.524 0.762)
			(end -1.524 -0.762)
			(stroke
				(width 0.1524)
				(type default)
			)
			(layer "F.SilkS")
		)
		(fp_line
			(start 1.524 0.762)
			(end -1.524 0.762)
			(stroke
				(width 0.1524)
				(type default)
			)
			(layer "F.SilkS")
		)
		(fp_line
			(start -1.524 -0.762)
			(end 1.524 -0.762)
			(stroke
				(width 0.1524)
				(type default)
			)
			(layer "F.SilkS")
		)
		(fp_line
			(start 1.524 -0.762)
			(end 1.524 0.762)
			(stroke
				(width 0.1524)
				(type default)
			)
			(layer "F.SilkS")
		)
		(fp_line
			(start -1.1049 0.724916)
			(end 1.1049 0.724916)
			(stroke
				(width 0.1)
				(type default)
			)
			(layer "F.Fab")
		)
		(fp_line
			(start 1.1049 0.724916)
			(end 1.1049 -0.724916)
			(stroke
				(width 0.1)
				(type default)
			)
			(layer "F.Fab")
		)
		(fp_line
			(start -1.1049 -0.724916)
			(end -1.1049 0.724916)
			(stroke
				(width 0.1)
				(type default)
			)
			(layer "F.Fab")
		)
		(fp_line
			(start 1.1049 -0.724916)
			(end -1.1049 -0.724916)
			(stroke
				(width 0.1)
				(type default)
			)
			(layer "F.Fab")
		)
		(pad "1" smd rect
			(at -0.889 0 90)
			(size 1.016 1.27)
			(layers "F.Cu" "F.Mask" "F.Paste")
			(net "P12V_E1S_0_R")
		)
		(pad "2" smd rect
			(at 0.889 0 90)
			(size 1.016 1.27)
			(layers "F.Cu" "F.Mask" "F.Paste")
			(net "GND")
		)
	)
	(footprint ""
		(layer "F.Cu")
		(at 41.33596 -434.086 -90)
		(property "Reference" "R3515"
			(at 0 0 270)
			(layer "F.SilkS")
			(hide yes)
			(effects
				(font
					(size 1.27 1.27)
				)
			)
		)
		(property "Value" ""
			(at 0 0 270)
			(layer "F.Fab")
			(effects
				(font
					(size 1.27 1.27)
				)
			)
		)
		(duplicate_pad_numbers_are_jumpers no)
		(fp_line
			(start -0.7874 0.4064)
			(end -0.7874 -0.4064)
			(stroke
				(width 0.1524)
				(type default)
			)
			(layer "F.SilkS")
		)
		(fp_line
			(start 0.7874 0.4064)
			(end -0.7874 0.4064)
			(stroke
				(width 0.1524)
				(type default)
			)
			(layer "F.SilkS")
		)
		(fp_line
			(start -0.7874 -0.4064)
			(end 0.7874 -0.4064)
			(stroke
				(width 0.1524)
				(type default)
			)
			(layer "F.SilkS")
		)
		(fp_line
			(start 0.7874 -0.4064)
			(end 0.7874 0.4064)
			(stroke
				(width 0.1524)
				(type default)
			)
			(layer "F.SilkS")
		)
		(fp_line
			(start -0.67945 0.3048)
			(end -0.67945 -0.305054)
			(stroke
				(width 0.1)
				(type default)
			)
			(layer "F.Fab")
		)
		(fp_line
			(start -0.12065 0.3048)
			(end -0.67945 0.3048)
			(stroke
				(width 0.1)
				(type default)
			)
			(layer "F.Fab")
		)
		(fp_line
			(start 0.120396 0.3048)
			(end 0.120396 0.2794)
			(stroke
				(width 0.1)
				(type default)
			)
			(layer "F.Fab")
		)
		(fp_line
			(start 0.67945 0.3048)
			(end 0.120396 0.3048)
			(stroke
				(width 0.1)
				(type default)
			)
			(layer "F.Fab")
		)
		(fp_line
			(start -0.12065 0.2794)
			(end -0.12065 0.3048)
			(stroke
				(width 0.1)
				(type default)
			)
			(layer "F.Fab")
		)
		(fp_line
			(start 0.120396 0.2794)
			(end -0.12065 0.2794)
			(stroke
				(width 0.1)
				(type default)
			)
			(layer "F.Fab")
		)
		(fp_line
			(start -0.12065 -0.2794)
			(end 0.12065 -0.2794)
			(stroke
				(width 0.1)
				(type default)
			)
			(layer "F.Fab")
		)
		(fp_line
			(start 0.12065 -0.2794)
			(end 0.12065 -0.3048)
			(stroke
				(width 0.1)
				(type default)
			)
			(layer "F.Fab")
		)
		(fp_line
			(start 0.12065 -0.3048)
			(end 0.67945 -0.3048)
			(stroke
				(width 0.1)
				(type default)
			)
			(layer "F.Fab")
		)
		(fp_line
			(start 0.67945 -0.3048)
			(end 0.67945 0.3048)
			(stroke
				(width 0.1)
				(type default)
			)
			(layer "F.Fab")
		)
		(fp_line
			(start -0.67945 -0.305054)
			(end -0.12065 -0.305054)
			(stroke
				(width 0.1)
				(type default)
			)
			(layer "F.Fab")
		)
		(fp_line
			(start -0.12065 -0.305054)
			(end -0.12065 -0.2794)
			(stroke
				(width 0.1)
				(type default)
			)
			(layer "F.Fab")
		)
		(pad "1" smd circle
			(at -0.40005 0 270)
			(size 0 0)
			(layers "F.Cu" "F.Mask" "F.Paste")
			(net "FM_SWB_PWR_EN_R1_BUF")
		)
		(pad "2" smd circle
			(at 0.40005 0 270)
			(size 0 0)
			(layers "F.Cu" "F.Mask" "F.Paste")
			(net "FM_SWB_PWR_EN_R_BUF")
		)
	)
)
